(kicad_pcb
	(version 20260206)
	(generator "pcbnew")
	(generator_version "10.0")
	(general
		(thickness 1.6)
		(legacy_teardrops no)
	)
	(paper "A4")
	(title_block
		(title "Bryce Canyon_IOM_IOC_16318-2_OCP.brd")
		(comment 1 "Bryce Canyon / footprints 478-483 of 1605")
	)
	(layers
		(0 "F.Cu" signal "TOP")
		(4 "In1.Cu" signal "L2GND")
		(6 "In2.Cu" signal "L3")
		(8 "In3.Cu" signal "L4VCC")
		(10 "In4.Cu" signal "L5VCC")
		(12 "In5.Cu" signal "L6")
		(14 "In6.Cu" signal "L7GND")
		(2 "B.Cu" signal "BOTTOM")
		(9 "F.Adhes" user "F.Adhesive")
		(11 "B.Adhes" user "B.Adhesive")
		(13 "F.Paste" user "Package Geometry/Pastemask Top")
		(15 "B.Paste" user "Package Geometry/Pastemask Bottom")
		(5 "F.SilkS" user "Ref Des/Silkscreen Top")
		(7 "B.SilkS" user "Ref Des/Silkscreen Bottom")
		(1 "F.Mask" user "Board Geometry/Soldermask Top")
		(3 "B.Mask" user "Board Geometry/Soldermask Bottom")
		(17 "Dwgs.User" user "User.Drawings")
		(19 "Cmts.User" user "User.Comments")
		(21 "Eco1.User" user "User.Eco1")
		(23 "Eco2.User" user "User.Eco2")
		(25 "Edge.Cuts" user "Board Geometry/Outline")
		(27 "Margin" user)
		(31 "F.CrtYd" user "Package Geometry/Place Bound Top")
		(29 "B.CrtYd" user "Package Geometry/Place Bound Bottom")
		(35 "F.Fab" user "Ref Des/Assembly Top")
		(33 "B.Fab" user "Ref Des/Assembly Bottom")
	)
	(footprint ""
		(layer "F.Cu")
		(at 188.930788 -122.010932 90)
		(property "Reference" "PU8"
			(at 0 0 90)
			(layer "F.SilkS")
			(hide yes)
			(effects
				(font
					(size 1.27 1.27)
				)
			)
		)
		(property "Value" "VT235WFQX-ADJ-1-GP"
			(at -5.8166 -7.7216 90)
			(unlocked yes)
			(layer "F.Fab")
			(hide yes)
			(effects
				(font
					(size 1.016 1.016)
					(thickness 0.1524)
				)
			)
		)
		(property "Device Type" "QFN19-1H40"
			(at -5.8166 -9.2456 90)
			(unlocked yes)
			(layer "F.Fab")
			(hide yes)
			(effects
				(font
					(size 1.016 1.016)
					(thickness 0.1524)
				)
			)
		)
		(duplicate_pad_numbers_are_jumpers no)
		(fp_line
			(start -1.4859 -3.0734)
			(end -2.7559 -3.0734)
			(stroke
				(width 0.1524)
				(type default)
			)
			(layer "F.SilkS")
		)
		(fp_line
			(start -2.7559 -3.0734)
			(end -2.7559 -1.8034)
			(stroke
				(width 0.1524)
				(type default)
			)
			(layer "F.SilkS")
		)
		(fp_line
			(start -1.253236 -2.821432)
			(end -1.253236 -3.329432)
			(stroke
				(width 0.1524)
				(type default)
			)
			(layer "F.SilkS")
		)
		(fp_line
			(start 2.821432 0.23876)
			(end 3.329432 0.23876)
			(stroke
				(width 0.1524)
				(type default)
			)
			(layer "F.SilkS")
		)
		(fp_line
			(start -2.7559 1.8034)
			(end -2.7559 3.0734)
			(stroke
				(width 0.1524)
				(type default)
			)
			(layer "F.SilkS")
		)
		(fp_line
			(start 0.766064 2.796032)
			(end 0.766064 3.558032)
			(stroke
				(width 0.1524)
				(type default)
			)
			(layer "F.SilkS")
		)
		(fp_line
			(start 3.0861 3.0734)
			(end 3.0861 1.8034)
			(stroke
				(width 0.1524)
				(type default)
			)
			(layer "F.SilkS")
		)
		(fp_line
			(start 1.8161 3.0734)
			(end 3.0861 3.0734)
			(stroke
				(width 0.1524)
				(type default)
			)
			(layer "F.SilkS")
		)
		(fp_line
			(start -2.7559 3.0734)
			(end -1.4859 3.0734)
			(stroke
				(width 0.1524)
				(type default)
			)
			(layer "F.SilkS")
		)
		(fp_poly
			(pts
				(xy 3.0861 -3.0734) (xy 1.8161 -3.0734) (xy 3.0861 -1.8034)
			)
			(stroke
				(width 0)
				(type default)
			)
			(fill yes)
			(layer "F.SilkS")
		)
		(fp_rect
			(start -2.2479 2.2479)
			(end 2.2479 -2.2479)
			(stroke
				(width 0)
				(type default)
			)
			(fill no)
			(layer "F.CrtYd")
		)
		(fp_poly
			(pts
				(xy -2.7559 -3.0734) (xy -2.7559 3.0734) (xy 3.0861 3.0734) (xy 3.0861 2.0193) (xy 2.2479 2.0193)
				(xy 2.2479 2.2479) (xy -2.2479 2.2479) (xy -2.2479 -2.2479) (xy 2.2479 -2.2479) (xy 2.2479 2.0066)
				(xy 3.0861 2.0066) (xy 3.0861 -3.0734)
			)
			(stroke
				(width 0)
				(type default)
			)
			(fill no)
			(layer "F.CrtYd")
		)
		(fp_rect
			(start -2.7559 3.0734)
			(end 3.0861 -3.0734)
			(stroke
				(width 0)
				(type default)
			)
			(fill no)
			(layer "F.Fab")
		)
		(pad "1" smd rect
			(at 1.249934 -2.135632 90)
			(size 0.3556 0.8382)
			(layers "F.Cu" "F.Mask" "F.Paste")
			(net "AGND_P0V975")
		)
		(pad "2" smd rect
			(at 0.750062 -2.135632 90)
			(size 0.3556 0.8382)
			(layers "F.Cu" "F.Mask" "F.Paste")
			(net "Net_658")
		)
		(pad "3" smd rect
			(at 0.249936 -2.135632 90)
			(size 0.3556 0.8382)
			(layers "F.Cu" "F.Mask" "F.Paste")
			(net "VT235_AVDD")
		)
		(pad "4" smd rect
			(at -0.249936 -0.687832 90)
			(size 0.3556 3.7338)
			(layers "F.Cu" "F.Mask" "F.Paste")
			(net "VT235_VDDH")
		)
		(pad "5" smd rect
			(at -1.249934 -1.335532 90)
			(size 0.3556 2.4384)
			(layers "F.Cu" "F.Mask" "F.Paste")
			(net "GND")
		)
		(pad "6" smd rect
			(at -1.75006 1.335532 90)
			(size 0.3556 2.4384)
			(layers "F.Cu" "F.Mask" "F.Paste")
			(net "VT235_VX")
		)
		(pad "7" smd rect
			(at -0.750062 1.335532 90)
			(size 0.3556 2.4384)
			(layers "F.Cu" "F.Mask" "F.Paste")
			(net "VT235_VX")
		)
		(pad "8" smd rect
			(at -0.249936 2.135632 90)
			(size 0.3556 0.8382)
			(layers "F.Cu" "F.Mask" "F.Paste")
			(net "VT235_BST")
		)
		(pad "9" smd rect
			(at 0.249936 2.135632 90)
			(size 0.3556 0.8382)
			(layers "F.Cu" "F.Mask" "F.Paste")
			(net "VT235_VDDL")
		)
		(pad "10" smd rect
			(at 0.750062 2.135632 90)
			(size 0.3556 0.8382)
			(layers "F.Cu" "F.Mask" "F.Paste")
			(net "VT235_AVDD")
		)
		(pad "11" smd rect
			(at 1.249934 2.135632 90)
			(size 0.3556 0.8382)
			(layers "F.Cu" "F.Mask" "F.Paste")
			(net "VT235_VFB")
		)
		(pad "12" smd rect
			(at 2.135632 1.75006 90)
			(size 0.8382 0.3556)
			(layers "F.Cu" "F.Mask" "F.Paste")
			(net "VT235_PGIN")
		)
		(pad "13" smd rect
			(at 2.135632 1.249934 90)
			(size 0.8382 0.3556)
			(layers "F.Cu" "F.Mask" "F.Paste")
			(net "VT235_VDES")
		)
		(pad "14" smd rect
			(at 2.135632 0.750062 90)
			(size 0.8382 0.3556)
			(layers "F.Cu" "F.Mask" "F.Paste")
			(net "VT235_VREF")
		)
		(pad "15" smd rect
			(at 2.135632 0.249936 90)
			(size 0.8382 0.3556)
			(layers "F.Cu" "F.Mask" "F.Paste")
			(net "VT235_BIAS")
		)
		(pad "16" smd rect
			(at 2.135632 -0.249936 90)
			(size 0.8382 0.3556)
			(layers "F.Cu" "F.Mask" "F.Paste")
			(net "VT235_IMAX")
		)
		(pad "17" smd rect
			(at 2.135632 -0.750062 90)
			(size 0.8382 0.3556)
			(layers "F.Cu" "F.Mask" "F.Paste")
			(net "IOM_FULL_PGOOD")
		)
		(pad "18" smd rect
			(at 2.135632 -1.249934 90)
			(size 0.8382 0.3556)
			(layers "F.Cu" "F.Mask" "F.Paste")
			(net "VT235_EN")
		)
		(pad "19" smd rect
			(at 2.135632 -1.75006 90)
			(size 0.8382 0.3556)
			(layers "F.Cu" "F.Mask" "F.Paste")
			(net "VT235_IRIP")
		)
	)
	(footprint ""
		(layer "F.Cu")
		(at 42.3164 -131.7498 180)
		(property "Reference" "R263"
			(at 0 0 180)
			(layer "F.SilkS")
			(hide yes)
			(effects
				(font
					(size 1.27 1.27)
				)
			)
		)
		(property "Value" "4K7R2F-GP"
			(at 0.064008 -3.993896 180)
			(unlocked yes)
			(layer "F.Fab")
			(hide yes)
			(effects
				(font
					(size 1.016 1.016)
					(thickness 0.1524)
				)
			)
		)
		(property "Device Type" "R402H16"
			(at 0.064008 -5.517896 180)
			(unlocked yes)
			(layer "F.Fab")
			(hide yes)
			(effects
				(font
					(size 1.016 1.016)
					(thickness 0.1524)
				)
			)
		)
		(duplicate_pad_numbers_are_jumpers no)
		(fp_line
			(start 0.508 -0.9398)
			(end -0.508 -0.9398)
			(stroke
				(width 0.1524)
				(type default)
			)
			(layer "F.SilkS")
		)
		(fp_line
			(start -0.508 -0.9398)
			(end -0.508 0.9398)
			(stroke
				(width 0.1524)
				(type default)
			)
			(layer "F.SilkS")
		)
		(fp_rect
			(start -0.508 0.9398)
			(end 0.508 -0.9398)
			(stroke
				(width 0)
				(type default)
			)
			(fill no)
			(layer "F.CrtYd")
		)
		(fp_rect
			(start -0.508 0.9398)
			(end 0.508 -0.9398)
			(stroke
				(width 0)
				(type default)
			)
			(fill no)
			(layer "F.Fab")
		)
		(pad "1" smd custom
			(at 0 -0.4445 180)
			(size 0.1397 0.1397)
			(layers "F.Cu" "F.Mask" "F.Paste")
			(net "P3V3_STBY")
			(options
				(clearance outline)
				(anchor circle)
			)
			(primitives
				(gr_poly
					(pts
						(arc
							(start -0.1778 -0.2794)
							(mid -0.249642 -0.249642)
							(end -0.2794 -0.1778)
						)
						(arc
							(start -0.2794 0.1778)
							(mid -0.249642 0.249642)
							(end -0.1778 0.2794)
						)
						(arc
							(start 0.1778 0.2794)
							(mid 0.249642 0.249642)
							(end 0.2794 0.1778)
						)
						(arc
							(start 0.2794 -0.1778)
							(mid 0.249642 -0.249642)
							(end 0.1778 -0.2794)
						)
					)
					(width 0)
					(fill yes)
				)
			)
		)
		(pad "2" smd custom
			(at 0 0.4445 180)
			(size 0.1397 0.1397)
			(layers "F.Cu" "F.Mask" "F.Paste")
			(net "BMC_GPIOY1")
			(options
				(clearance outline)
				(anchor circle)
			)
			(primitives
				(gr_poly
					(pts
						(arc
							(start -0.1778 -0.2794)
							(mid -0.249642 -0.249642)
							(end -0.2794 -0.1778)
						)
						(arc
							(start -0.2794 0.1778)
							(mid -0.249642 0.249642)
							(end -0.1778 0.2794)
						)
						(arc
							(start 0.1778 0.2794)
							(mid 0.249642 0.249642)
							(end 0.2794 0.1778)
						)
						(arc
							(start 0.2794 -0.1778)
							(mid 0.249642 -0.249642)
							(end 0.1778 -0.2794)
						)
					)
					(width 0)
					(fill yes)
				)
			)
		)
	)
	(footprint ""
		(layer "F.Cu")
		(at 61.543184 -142.417292 90)
		(property "Reference" "R155"
			(at 0 0 90)
			(layer "F.SilkS")
			(hide yes)
			(effects
				(font
					(size 1.27 1.27)
				)
			)
		)
		(property "Value" "0R2J-2-GP"
			(at 0.064008 -3.993896 90)
			(unlocked yes)
			(layer "F.Fab")
			(hide yes)
			(effects
				(font
					(size 1.016 1.016)
					(thickness 0.1524)
				)
			)
		)
		(property "Device Type" "R402H16"
			(at 0.064008 -5.517896 90)
			(unlocked yes)
			(layer "F.Fab")
			(hide yes)
			(effects
				(font
					(size 1.016 1.016)
					(thickness 0.1524)
				)
			)
		)
		(duplicate_pad_numbers_are_jumpers no)
		(fp_line
			(start 0.508 -0.9398)
			(end -0.508 -0.9398)
			(stroke
				(width 0.1524)
				(type default)
			)
			(layer "F.SilkS")
		)
		(fp_line
			(start -0.508 -0.9398)
			(end -0.508 0.9398)
			(stroke
				(width 0.1524)
				(type default)
			)
			(layer "F.SilkS")
		)
		(fp_rect
			(start -0.508 0.9398)
			(end 0.508 -0.9398)
			(stroke
				(width 0)
				(type default)
			)
			(fill no)
			(layer "F.CrtYd")
		)
		(fp_rect
			(start -0.508 0.9398)
			(end 0.508 -0.9398)
			(stroke
				(width 0)
				(type default)
			)
			(fill no)
			(layer "F.Fab")
		)
		(pad "1" smd custom
			(at 0 -0.4445 90)
			(size 0.1397 0.1397)
			(layers "F.Cu" "F.Mask" "F.Paste")
			(net "BMC_SMB11_CLK")
			(options
				(clearance outline)
				(anchor circle)
			)
			(primitives
				(gr_poly
					(pts
						(arc
							(start -0.1778 -0.2794)
							(mid -0.249642 -0.249642)
							(end -0.2794 -0.1778)
						)
						(arc
							(start -0.2794 0.1778)
							(mid -0.249642 0.249642)
							(end -0.1778 0.2794)
						)
						(arc
							(start 0.1778 0.2794)
							(mid 0.249642 0.249642)
							(end 0.2794 0.1778)
						)
						(arc
							(start 0.2794 -0.1778)
							(mid 0.249642 -0.249642)
							(end 0.1778 -0.2794)
						)
					)
					(width 0)
					(fill yes)
				)
			)
		)
		(pad "2" smd custom
			(at 0 0.4445 90)
			(size 0.1397 0.1397)
			(layers "F.Cu" "F.Mask" "F.Paste")
			(net "I2C_EXP_RMT_SCL_OUT")
			(options
				(clearance outline)
				(anchor circle)
			)
			(primitives
				(gr_poly
					(pts
						(arc
							(start -0.1778 -0.2794)
							(mid -0.249642 -0.249642)
							(end -0.2794 -0.1778)
						)
						(arc
							(start -0.2794 0.1778)
							(mid -0.249642 0.249642)
							(end -0.1778 0.2794)
						)
						(arc
							(start 0.1778 0.2794)
							(mid 0.249642 0.249642)
							(end 0.2794 0.1778)
						)
						(arc
							(start 0.2794 -0.1778)
							(mid 0.249642 -0.249642)
							(end 0.1778 -0.2794)
						)
					)
					(width 0)
					(fill yes)
				)
			)
		)
	)
	(footprint ""
		(layer "F.Cu")
		(at 68.199 -145.3134 -90)
		(property "Reference" "R380"
			(at 0 0 270)
			(layer "F.SilkS")
			(hide yes)
			(effects
				(font
					(size 1.27 1.27)
				)
			)
		)
		(property "Value" "4K7R2F-GP"
			(at 0.064008 -3.993896 270)
			(unlocked yes)
			(layer "F.Fab")
			(hide yes)
			(effects
				(font
					(size 1.016 1.016)
					(thickness 0.1524)
				)
			)
		)
		(property "Device Type" "R402H16"
			(at 0.064008 -5.517896 270)
			(unlocked yes)
			(layer "F.Fab")
			(hide yes)
			(effects
				(font
					(size 1.016 1.016)
					(thickness 0.1524)
				)
			)
		)
		(duplicate_pad_numbers_are_jumpers no)
		(fp_line
			(start -0.508 -0.9398)
			(end -0.508 0.9398)
			(stroke
				(width 0.1524)
				(type default)
			)
			(layer "F.SilkS")
		)
		(fp_line
			(start 0.508 -0.9398)
			(end -0.508 -0.9398)
			(stroke
				(width 0.1524)
				(type default)
			)
			(layer "F.SilkS")
		)
		(fp_rect
			(start -0.508 0.9398)
			(end 0.508 -0.9398)
			(stroke
				(width 0)
				(type default)
			)
			(fill no)
			(layer "F.CrtYd")
		)
		(fp_rect
			(start -0.508 0.9398)
			(end 0.508 -0.9398)
			(stroke
				(width 0)
				(type default)
			)
			(fill no)
			(layer "F.Fab")
		)
		(pad "1" smd custom
			(at 0 -0.4445 270)
			(size 0.1397 0.1397)
			(layers "F.Cu" "F.Mask" "F.Paste")
			(net "P3V3_STBY")
			(options
				(clearance outline)
				(anchor circle)
			)
			(primitives
				(gr_poly
					(pts
						(arc
							(start -0.1778 -0.2794)
							(mid -0.249642 -0.249642)
							(end -0.2794 -0.1778)
						)
						(arc
							(start -0.2794 0.1778)
							(mid -0.249642 0.249642)
							(end -0.1778 0.2794)
						)
						(arc
							(start 0.1778 0.2794)
							(mid 0.249642 0.249642)
							(end 0.2794 0.1778)
						)
						(arc
							(start 0.2794 -0.1778)
							(mid 0.249642 -0.249642)
							(end 0.1778 -0.2794)
						)
					)
					(width 0)
					(fill yes)
				)
			)
		)
		(pad "2" smd custom
			(at 0 0.4445 270)
			(size 0.1397 0.1397)
			(layers "F.Cu" "F.Mask" "F.Paste")
			(net "NCSI_TXEN")
			(options
				(clearance outline)
				(anchor circle)
			)
			(primitives
				(gr_poly
					(pts
						(arc
							(start -0.1778 -0.2794)
							(mid -0.249642 -0.249642)
							(end -0.2794 -0.1778)
						)
						(arc
							(start -0.2794 0.1778)
							(mid -0.249642 0.249642)
							(end -0.1778 0.2794)
						)
						(arc
							(start 0.1778 0.2794)
							(mid 0.249642 0.249642)
							(end 0.2794 0.1778)
						)
						(arc
							(start 0.2794 -0.1778)
							(mid 0.249642 -0.249642)
							(end 0.1778 -0.2794)
						)
					)
					(width 0)
					(fill yes)
				)
			)
		)
	)
	(footprint ""
		(layer "F.Cu")
		(at 159.644588 -93.504512 -90)
		(property "Reference" "C482"
			(at 0 0 270)
			(layer "F.SilkS")
			(hide yes)
			(effects
				(font
					(size 1.27 1.27)
				)
			)
		)
		(property "Value" "SCD1U16V2KX-3GP"
			(at 1.1811 -2.7051 270)
			(unlocked yes)
			(layer "F.Fab")
			(hide yes)
			(effects
				(font
					(size 1.016 1.016)
					(thickness 0.1524)
				)
			)
		)
		(property "Device Type" "C402H22"
			(at 1.1811 -4.2291 270)
			(unlocked yes)
			(layer "F.Fab")
			(hide yes)
			(effects
				(font
					(size 1.016 1.016)
					(thickness 0.1524)
				)
			)
		)
		(duplicate_pad_numbers_are_jumpers no)
		(fp_rect
			(start -0.4318 0.9525)
			(end 0.4318 -0.9525)
			(stroke
				(width 0)
				(type default)
			)
			(fill no)
			(layer "F.CrtYd")
		)
		(fp_rect
			(start -0.4318 0.9525)
			(end 0.4318 -0.9525)
			(stroke
				(width 0)
				(type default)
			)
			(fill no)
			(layer "F.Fab")
		)
		(pad "1" smd custom
			(at 0 -0.4445 270)
			(size 0.1524 0.1524)
			(layers "F.Cu" "F.Mask" "F.Paste")
			(net "U43_VREF2")
			(options
				(clearance outline)
				(anchor circle)
			)
			(primitives
				(gr_poly
					(pts
						(arc
							(start 0.3048 -0.2032)
							(mid 0.275042 -0.275042)
							(end 0.2032 -0.3048)
						)
						(arc
							(start -0.2032 -0.3048)
							(mid -0.275042 -0.275042)
							(end -0.3048 -0.2032)
						)
						(arc
							(start -0.3048 0.2032)
							(mid -0.275042 0.275042)
							(end -0.2032 0.3048)
						)
						(arc
							(start 0.2032 0.3048)
							(mid 0.275042 0.275042)
							(end 0.3048 0.2032)
						)
					)
					(width 0)
					(fill yes)
				)
			)
		)
		(pad "2" smd custom
			(at 0 0.4445 270)
			(size 0.1524 0.1524)
			(layers "F.Cu" "F.Mask" "F.Paste")
			(net "GND")
			(options
				(clearance outline)
				(anchor circle)
			)
			(primitives
				(gr_poly
					(pts
						(arc
							(start 0.3048 -0.2032)
							(mid 0.275042 -0.275042)
							(end 0.2032 -0.3048)
						)
						(arc
							(start -0.2032 -0.3048)
							(mid -0.275042 -0.275042)
							(end -0.3048 -0.2032)
						)
						(arc
							(start -0.3048 0.2032)
							(mid -0.275042 0.275042)
							(end -0.2032 0.3048)
						)
						(arc
							(start 0.2032 0.3048)
							(mid 0.275042 0.275042)
							(end 0.3048 0.2032)
						)
					)
					(width 0)
					(fill yes)
				)
			)
		)
	)
	(footprint ""
		(layer "F.Cu")
		(at 29.832046 -176.618138 180)
		(property "Reference" "R494"
			(at 0 0 180)
			(layer "F.SilkS")
			(hide yes)
			(effects
				(font
					(size 1.27 1.27)
				)
			)
		)
		(property "Value" "57K6R2D-GP"
			(at 0.064008 -3.993896 180)
			(unlocked yes)
			(layer "F.Fab")
			(hide yes)
			(effects
				(font
					(size 1.016 1.016)
					(thickness 0.1524)
				)
			)
		)
		(property "Device Type" "R402H16"
			(at 0.064008 -5.517896 180)
			(unlocked yes)
			(layer "F.Fab")
			(hide yes)
			(effects
				(font
					(size 1.016 1.016)
					(thickness 0.1524)
				)
			)
		)
		(duplicate_pad_numbers_are_jumpers no)
		(fp_line
			(start 0.508 -0.9398)
			(end -0.508 -0.9398)
			(stroke
				(width 0.1524)
				(type default)
			)
			(layer "F.SilkS")
		)
		(fp_line
			(start -0.508 -0.9398)
			(end -0.508 0.9398)
			(stroke
				(width 0.1524)
				(type default)
			)
			(layer "F.SilkS")
		)
		(fp_rect
			(start -0.508 0.9398)
			(end 0.508 -0.9398)
			(stroke
				(width 0)
				(type default)
			)
			(fill no)
			(layer "F.CrtYd")
		)
		(fp_rect
			(start -0.508 0.9398)
			(end 0.508 -0.9398)
			(stroke
				(width 0)
				(type default)
			)
			(fill no)
			(layer "F.Fab")
		)
		(pad "1" smd custom
			(at 0 -0.4445 180)
			(size 0.1397 0.1397)
			(layers "F.Cu" "F.Mask" "F.Paste")
			(net "AGND_P3V3_STBY")
			(options
				(clearance outline)
				(anchor circle)
			)
			(primitives
				(gr_poly
					(pts
						(arc
							(start -0.1778 -0.2794)
							(mid -0.249642 -0.249642)
							(end -0.2794 -0.1778)
						)
						(arc
							(start -0.2794 0.1778)
							(mid -0.249642 0.249642)
							(end -0.1778 0.2794)
						)
						(arc
							(start 0.1778 0.2794)
							(mid 0.249642 0.249642)
							(end 0.2794 0.1778)
						)
						(arc
							(start 0.2794 -0.1778)
							(mid 0.249642 -0.249642)
							(end 0.1778 -0.2794)
						)
					)
					(width 0)
					(fill yes)
				)
			)
		)
		(pad "2" smd custom
			(at 0 0.4445 180)
			(size 0.1397 0.1397)
			(layers "F.Cu" "F.Mask" "F.Paste")
			(net "P3V3_STBY_TRIP")
			(options
				(clearance outline)
				(anchor circle)
			)
			(primitives
				(gr_poly
					(pts
						(arc
							(start -0.1778 -0.2794)
							(mid -0.249642 -0.249642)
							(end -0.2794 -0.1778)
						)
						(arc
							(start -0.2794 0.1778)
							(mid -0.249642 0.249642)
							(end -0.1778 0.2794)
						)
						(arc
							(start 0.1778 0.2794)
							(mid 0.249642 0.249642)
							(end 0.2794 0.1778)
						)
						(arc
							(start 0.2794 -0.1778)
							(mid 0.249642 -0.249642)
							(end 0.1778 -0.2794)
						)
					)
					(width 0)
					(fill yes)
				)
			)
		)
	)
)
